(kicad_pcb
	(version 20260206)
	(generator "pcbnew")
	(generator_version "10.0")
	(general
		(thickness 1.6)
		(legacy_teardrops no)
	)
	(paper "A4")
	(title_block
		(title "Bryce Canyon_F.DPB_16315-1-OCP.brd")
		(comment 1 "Bryce Canyon / footprints 26-29 of 2223")
	)
	(layers
		(0 "F.Cu" signal "TOP")
		(4 "In1.Cu" signal "L2GND")
		(6 "In2.Cu" signal "L3")
		(8 "In3.Cu" signal "L4GND")
		(10 "In4.Cu" signal "L5")
		(12 "In5.Cu" signal "L6VCC")
		(14 "In6.Cu" signal "L7VCC")
		(16 "In7.Cu" signal "L8")
		(18 "In8.Cu" signal "L9GND")
		(20 "In9.Cu" signal "L10")
		(22 "In10.Cu" signal "L11GND")
		(2 "B.Cu" signal "BOTTOM")
		(9 "F.Adhes" user "F.Adhesive")
		(11 "B.Adhes" user "B.Adhesive")
		(13 "F.Paste" user "Package Geometry/Pastemask Top")
		(15 "B.Paste" user "Package Geometry/Pastemask Bottom")
		(5 "F.SilkS" user "Ref Des/Silkscreen Top")
		(7 "B.SilkS" user "Ref Des/Silkscreen Bottom")
		(1 "F.Mask" user "Board Geometry/Soldermask Top")
		(3 "B.Mask" user "Board Geometry/Soldermask Bottom")
		(17 "Dwgs.User" user "User.Drawings")
		(19 "Cmts.User" user "User.Comments")
		(21 "Eco1.User" user "User.Eco1")
		(23 "Eco2.User" user "User.Eco2")
		(25 "Edge.Cuts" user "Board Geometry/Outline")
		(27 "Margin" user)
		(31 "F.CrtYd" user "Package Geometry/Place Bound Top")
		(29 "B.CrtYd" user "Package Geometry/Place Bound Bottom")
		(35 "F.Fab" user "Ref Des/Assembly Top")
		(33 "B.Fab" user "Ref Des/Assembly Bottom")
	)
	(footprint ""
		(layer "F.Cu")
		(at 325.550022 -172.909992 -90)
		(property "Reference" "HDDSAS18"
			(at 0 0 270)
			(layer "F.SilkS")
			(hide yes)
			(effects
				(font
					(size 1.27 1.27)
				)
			)
		)
		(property "Value" "SKT-SAS15P-14P-45-GP"
			(at -20.7645 -8.9789 270)
			(unlocked yes)
			(layer "F.Fab")
			(hide yes)
			(effects
				(font
					(size 1.016 1.016)
					(thickness 0.1524)
				)
			)
		)
		(property "Device Type" "10120818-001C-TRLF"
			(at -20.7645 -10.5029 270)
			(unlocked yes)
			(layer "F.Fab")
			(hide yes)
			(effects
				(font
					(size 1.016 1.016)
					(thickness 0.1524)
				)
			)
		)
		(duplicate_pad_numbers_are_jumpers no)
		(fp_line
			(start 1.651 4.2926)
			(end 1.651 3.0099)
			(stroke
				(width 0.1524)
				(type default)
			)
			(layer "F.SilkS")
		)
		(fp_line
			(start 8.509 4.2926)
			(end 1.651 4.2926)
			(stroke
				(width 0.1524)
				(type default)
			)
			(layer "F.SilkS")
		)
		(fp_line
			(start -23.4188 3.0099)
			(end -23.4188 -3.2512)
			(stroke
				(width 0.1524)
				(type default)
			)
			(layer "F.SilkS")
		)
		(fp_line
			(start 1.651 3.0099)
			(end -23.4188 3.0099)
			(stroke
				(width 0.1524)
				(type default)
			)
			(layer "F.SilkS")
		)
		(fp_line
			(start 8.509 3.0099)
			(end 8.509 4.2926)
			(stroke
				(width 0.1524)
				(type default)
			)
			(layer "F.SilkS")
		)
		(fp_line
			(start 23.4188 3.0099)
			(end 8.509 3.0099)
			(stroke
				(width 0.1524)
				(type default)
			)
			(layer "F.SilkS")
		)
		(fp_line
			(start -23.4188 -3.2512)
			(end 23.4188 -3.2512)
			(stroke
				(width 0.1524)
				(type default)
			)
			(layer "F.SilkS")
		)
		(fp_line
			(start 23.4188 -3.2512)
			(end 23.4188 3.0099)
			(stroke
				(width 0.1524)
				(type default)
			)
			(layer "F.SilkS")
		)
		(fp_line
			(start 15.5067 -3.3401)
			(end 16.2687 -3.3401)
			(stroke
				(width 0.3302)
				(type default)
			)
			(layer "F.SilkS")
		)
		(fp_poly
			(pts
				(xy 15.868904 -3.230372) (xy 16.503904 -3.865372) (xy 15.233904 -3.865372)
			)
			(stroke
				(width 0)
				(type default)
			)
			(fill yes)
			(layer "F.SilkS")
		)
		(fp_poly
			(pts
				(xy -22.8727 -2.7559) (xy 22.8727 -2.7559) (xy 22.8727 2.7559) (xy 8.255 2.7559) (xy 8.255 3.5179)
				(xy 1.905 3.5179) (xy 1.905 2.7559) (xy -22.8727 2.7559)
			)
			(stroke
				(width 0)
				(type default)
			)
			(fill no)
			(layer "F.CrtYd")
		)
		(fp_poly
			(pts
				(xy 1.397 4.5466) (xy 1.397 3.2639) (xy -23.6728 3.2639) (xy -23.6728 -3.5052) (xy 23.6728 -3.5052)
				(xy 23.6728 -0.00635) (xy 22.8727 -0.00635) (xy 22.8727 -2.7559) (xy -22.8727 -2.7559) (xy -22.8727 2.7559)
				(xy 1.905 2.7559) (xy 1.905 3.5179) (xy 8.255 3.5179) (xy 8.255 2.7559) (xy 22.8727 2.7559) (xy 22.8727 0.00635)
				(xy 23.6728 0.00635) (xy 23.6728 3.2639) (xy 8.763 3.2639) (xy 8.763 4.5466)
			)
			(stroke
				(width 0)
				(type default)
			)
			(fill no)
			(layer "F.CrtYd")
		)
		(fp_poly
			(pts
				(xy 1.397 4.5466) (xy 1.397 3.2639) (xy -23.6728 3.2639) (xy -23.6728 -3.5052) (xy 23.6728 -3.5052)
				(xy 23.6728 3.2639) (xy 8.763 3.2639) (xy 8.763 4.5466)
			)
			(stroke
				(width 0)
				(type default)
			)
			(fill no)
			(layer "F.Fab")
		)
		(pad "" np_thru_hole circle
			(at -18.874994 0 270)
			(size 0.254 0.254)
			(drill 1.3462)
			(layers "*.Cu" "*.Mask")
			(clearance 0.9017)
			(thermal_gap 0.9017)
		)
		(pad "" np_thru_hole circle
			(at 18.874994 0 270)
			(size 0.254 0.254)
			(drill 0.9398)
			(layers "*.Cu" "*.Mask")
			(clearance 0.6985)
			(thermal_gap 0.6985)
		)
		(pad "G1" smd rect
			(at 21.874988 0 270)
			(size 2.5908 2.5908)
			(layers "F.Cu" "F.Mask" "F.Paste")
			(net "GND")
		)
		(pad "G2" smd rect
			(at -21.874988 0 270)
			(size 2.5908 2.5908)
			(layers "F.Cu" "F.Mask" "F.Paste")
			(net "GND")
		)
		(pad "P1" smd rect
			(at 1.905 -1.82499 270)
			(size 0.6096 2.3622)
			(layers "F.Cu" "F.Mask" "F.Paste")
			(net "Net_2126")
		)
		(pad "P2" smd rect
			(at 0.635 -1.82499 270)
			(size 0.6096 2.3622)
			(layers "F.Cu" "F.Mask" "F.Paste")
			(net "Net_2127")
		)
		(pad "P3" smd rect
			(at -0.635 -1.82499 270)
			(size 0.6096 2.3622)
			(layers "F.Cu" "F.Mask" "F.Paste")
			(net "Net_2128")
		)
		(pad "P4" smd rect
			(at -1.905 -1.82499 270)
			(size 0.6096 2.3622)
			(layers "F.Cu" "F.Mask" "F.Paste")
			(net "GND")
		)
		(pad "P5" smd rect
			(at -3.175 -1.82499 270)
			(size 0.6096 2.3622)
			(layers "F.Cu" "F.Mask" "F.Paste")
			(net "HDD_PRSNT_18")
		)
		(pad "P6" smd rect
			(at -4.445 -1.82499 270)
			(size 0.6096 2.3622)
			(layers "F.Cu" "F.Mask" "F.Paste")
			(net "GND")
		)
		(pad "P7" smd rect
			(at -5.715 -1.82499 270)
			(size 0.6096 2.3622)
			(layers "F.Cu" "F.Mask" "F.Paste")
			(net "5V_PRE_18")
		)
		(pad "P8" smd rect
			(at -6.985 -1.82499 270)
			(size 0.6096 2.3622)
			(layers "F.Cu" "F.Mask" "F.Paste")
			(net "P5V_HDD18")
		)
		(pad "P9" smd rect
			(at -8.255 -1.82499 270)
			(size 0.6096 2.3622)
			(layers "F.Cu" "F.Mask" "F.Paste")
			(net "P5V_HDD18")
		)
		(pad "P10" smd rect
			(at -9.525 -1.82499 270)
			(size 0.6096 2.3622)
			(layers "F.Cu" "F.Mask" "F.Paste")
			(net "GND")
		)
		(pad "P11" smd rect
			(at -10.795 -1.82499 270)
			(size 0.6096 2.3622)
			(layers "F.Cu" "F.Mask" "F.Paste")
			(net "ACT_HDD_18")
		)
		(pad "P12" smd rect
			(at -12.065 -1.82499 270)
			(size 0.6096 2.3622)
			(layers "F.Cu" "F.Mask" "F.Paste")
			(net "GND")
		)
		(pad "P13" smd rect
			(at -13.335 -1.82499 270)
			(size 0.6096 2.3622)
			(layers "F.Cu" "F.Mask" "F.Paste")
			(net "12V_PRE_18")
		)
		(pad "P14" smd rect
			(at -14.605 -1.82499 270)
			(size 0.6096 2.3622)
			(layers "F.Cu" "F.Mask" "F.Paste")
			(net "P12V_HDD18")
		)
		(pad "P15" smd rect
			(at -15.875 -1.82499 270)
			(size 0.6096 2.3622)
			(layers "F.Cu" "F.Mask" "F.Paste")
			(net "P12V_HDD18")
		)
		(pad "S1" smd rect
			(at 15.875 -1.82499 270)
			(size 0.6096 2.3622)
			(layers "F.Cu" "F.Mask" "F.Paste")
			(net "GND")
		)
		(pad "S2" smd rect
			(at 14.605 -1.82499 270)
			(size 0.6096 2.3622)
			(layers "F.Cu" "F.Mask" "F.Paste")
			(net "SAS_HDD_RX_P18")
		)
		(pad "S3" smd rect
			(at 13.335 -1.82499 270)
			(size 0.6096 2.3622)
			(layers "F.Cu" "F.Mask" "F.Paste")
			(net "SAS_HDD_RX_N18")
		)
		(pad "S4" smd rect
			(at 12.065 -1.82499 270)
			(size 0.6096 2.3622)
			(layers "F.Cu" "F.Mask" "F.Paste")
			(net "GND")
		)
		(pad "S5" smd rect
			(at 10.795 -1.82499 270)
			(size 0.6096 2.3622)
			(layers "F.Cu" "F.Mask" "F.Paste")
			(net "PHY_DRV_A_TO_SCC_A_18_DN")
		)
		(pad "S6" smd rect
			(at 9.525 -1.82499 270)
			(size 0.6096 2.3622)
			(layers "F.Cu" "F.Mask" "F.Paste")
			(net "PHY_DRV_A_TO_SCC_A_18_DP")
		)
		(pad "S7" smd rect
			(at 8.255 -1.82499 270)
			(size 0.6096 2.3622)
			(layers "F.Cu" "F.Mask" "F.Paste")
			(net "GND")
		)
		(pad "S8" smd rect
			(at 7.480046 2.845054 270)
			(size 0.508 2.3622)
			(layers "F.Cu" "F.Mask" "F.Paste")
			(net "GND")
		)
		(pad "S9" smd rect
			(at 6.679946 2.845054 270)
			(size 0.508 2.3622)
			(layers "F.Cu" "F.Mask" "F.Paste")
			(net "Net_455")
		)
		(pad "S10" smd rect
			(at 5.8801 2.845054 270)
			(size 0.508 2.3622)
			(layers "F.Cu" "F.Mask" "F.Paste")
			(net "Net_347")
		)
		(pad "S11" smd rect
			(at 5.08 2.845054 270)
			(size 0.508 2.3622)
			(layers "F.Cu" "F.Mask" "F.Paste")
			(net "GND")
		)
		(pad "S12" smd rect
			(at 4.2799 2.845054 270)
			(size 0.508 2.3622)
			(layers "F.Cu" "F.Mask" "F.Paste")
			(net "Net_383")
		)
		(pad "S13" smd rect
			(at 3.480054 2.845054 270)
			(size 0.508 2.3622)
			(layers "F.Cu" "F.Mask" "F.Paste")
			(net "Net_419")
		)
		(pad "S14" smd rect
			(at 2.679954 2.845054 270)
			(size 0.508 2.3622)
			(layers "F.Cu" "F.Mask" "F.Paste")
			(net "GND")
		)
		(zone
			(layer "F.Cu")
			(hatch none 0.5)
			(connect_pads
				(clearance 0)
			)
			(min_thickness 0.25)
			(keepout
				(tracks not_allowed)
				(vias allowed)
				(pads allowed)
				(copperpour not_allowed)
				(footprints allowed)
			)
			(placement
				(enabled no)
				(sheetname "")
			)
			(fill
				(thermal_gap 0.5)
				(thermal_bridge_width 0.5)
				(island_removal_mode 0)
			)
			(polygon
				(pts
					(xy 329.207622 -189.648592) (xy 322.133722 -189.648592) (xy 322.133722 -196.582792) (xy 323.238622 -196.582792)
					(xy 323.238622 -192.467992) (xy 327.861422 -192.467992) (xy 327.861422 -196.582792) (xy 329.207622 -196.582792)
				)
			)
		)
		(zone
			(layer "F.Cu")
			(hatch none 0.5)
			(connect_pads
				(clearance 0)
			)
			(min_thickness 0.25)
			(keepout
				(tracks allowed)
				(vias not_allowed)
				(pads allowed)
				(copperpour not_allowed)
				(footprints allowed)
			)
			(placement
				(enabled no)
				(sheetname "")
			)
			(fill
				(thermal_gap 0.5)
				(thermal_bridge_width 0.5)
				(island_removal_mode 0)
			)
			(polygon
				(pts
					(xy 329.207622 -189.648592) (xy 322.133722 -189.648592) (xy 322.133722 -196.582792) (xy 323.238622 -196.582792)
					(xy 323.238622 -192.467992) (xy 327.861422 -192.467992) (xy 327.861422 -196.582792) (xy 329.207622 -196.582792)
				)
			)
		)
		(zone
			(layer "F.Cu")
			(hatch none 0.5)
			(connect_pads
				(clearance 0)
			)
			(min_thickness 0.25)
			(keepout
				(tracks not_allowed)
				(vias allowed)
				(pads allowed)
				(copperpour not_allowed)
				(footprints allowed)
			)
			(placement
				(enabled no)
				(sheetname "")
			)
			(fill
				(thermal_gap 0.5)
				(thermal_bridge_width 0.5)
				(island_removal_mode 0)
			)
			(polygon
				(pts
					(xy 329.207622 -156.171392) (xy 322.133722 -156.171392) (xy 322.133722 -149.237192) (xy 323.238622 -149.237192)
					(xy 323.238622 -153.351992) (xy 327.861422 -153.351992) (xy 327.861422 -149.237192) (xy 329.207622 -149.237192)
				)
			)
		)
		(zone
			(layer "F.Cu")
			(hatch none 0.5)
			(connect_pads
				(clearance 0)
			)
			(min_thickness 0.25)
			(keepout
				(tracks allowed)
				(vias not_allowed)
				(pads allowed)
				(copperpour not_allowed)
				(footprints allowed)
			)
			(placement
				(enabled no)
				(sheetname "")
			)
			(fill
				(thermal_gap 0.5)
				(thermal_bridge_width 0.5)
				(island_removal_mode 0)
			)
			(polygon
				(pts
					(xy 329.207622 -156.171392) (xy 322.133722 -156.171392) (xy 322.133722 -149.237192) (xy 323.238622 -149.237192)
					(xy 323.238622 -153.351992) (xy 327.861422 -153.351992) (xy 327.861422 -149.237192) (xy 329.207622 -149.237192)
				)
			)
		)
		(zone
			(layers "F.Cu" "B.Cu" "In1.Cu" "In2.Cu" "In3.Cu" "In4.Cu" "In5.Cu" "In6.Cu"
				"In7.Cu" "In8.Cu" "In9.Cu" "In10.Cu"
			)
			(hatch none 0.5)
			(connect_pads
				(clearance 0)
			)
			(min_thickness 0.25)
			(keepout
				(tracks not_allowed)
				(vias allowed)
				(pads allowed)
				(copperpour not_allowed)
				(footprints allowed)
			)
			(placement
				(enabled no)
				(sheetname "")
			)
			(fill
				(thermal_gap 0.5)
				(thermal_bridge_width 0.5)
				(island_removal_mode 0)
			)
			(polygon
				(pts
					(arc
						(start 326.324722 -154.034998)
						(mid 324.775322 -154.034998)
						(end 326.324722 -154.034998)
					)
				)
			)
		)
		(zone
			(layers "F.Cu" "B.Cu" "In1.Cu" "In2.Cu" "In3.Cu" "In4.Cu" "In5.Cu" "In6.Cu"
				"In7.Cu" "In8.Cu" "In9.Cu" "In10.Cu"
			)
			(hatch none 0.5)
			(connect_pads
				(clearance 0)
			)
			(min_thickness 0.25)
			(keepout
				(tracks not_allowed)
				(vias allowed)
				(pads allowed)
				(copperpour not_allowed)
				(footprints allowed)
			)
			(placement
				(enabled no)
				(sheetname "")
			)
			(fill
				(thermal_gap 0.5)
				(thermal_bridge_width 0.5)
				(island_removal_mode 0)
			)
			(polygon
				(pts
					(arc
						(start 326.527922 -191.784986)
						(mid 324.572122 -191.784986)
						(end 326.527922 -191.784986)
					)
				)
			)
		)
	)
	(footprint ""
		(layer "F.Cu")
		(at 268.232382 19.366738 90)
		(property "Reference" "C89"
			(at 0 0 90)
			(layer "F.SilkS")
			(hide yes)
			(effects
				(font
					(size 1.27 1.27)
				)
			)
		)
		(property "Value" "SCD1U16V2KX-3GP"
			(at 1.1811 -2.7051 90)
			(unlocked yes)
			(layer "F.Fab")
			(hide yes)
			(effects
				(font
					(size 1.016 1.016)
					(thickness 0.1524)
				)
			)
		)
		(property "Device Type" "C402H22"
			(at 1.1811 -4.2291 90)
			(unlocked yes)
			(layer "F.Fab")
			(hide yes)
			(effects
				(font
					(size 1.016 1.016)
					(thickness 0.1524)
				)
			)
		)
		(duplicate_pad_numbers_are_jumpers no)
		(fp_rect
			(start -0.4318 0.9525)
			(end 0.4318 -0.9525)
			(stroke
				(width 0)
				(type default)
			)
			(fill no)
			(layer "F.CrtYd")
		)
		(fp_rect
			(start -0.4318 0.9525)
			(end 0.4318 -0.9525)
			(stroke
				(width 0)
				(type default)
			)
			(fill no)
			(layer "F.Fab")
		)
		(pad "1" smd custom
			(at 0 -0.4445 90)
			(size 0.1524 0.1524)
			(layers "F.Cu" "F.Mask" "F.Paste")
			(net "P5V_USB_B")
			(options
				(clearance outline)
				(anchor circle)
			)
			(primitives
				(gr_poly
					(pts
						(arc
							(start 0.3048 -0.2032)
							(mid 0.275042 -0.275042)
							(end 0.2032 -0.3048)
						)
						(arc
							(start -0.2032 -0.3048)
							(mid -0.275042 -0.275042)
							(end -0.3048 -0.2032)
						)
						(arc
							(start -0.3048 0.2032)
							(mid -0.275042 0.275042)
							(end -0.2032 0.3048)
						)
						(arc
							(start 0.2032 0.3048)
							(mid 0.275042 0.275042)
							(end 0.3048 0.2032)
						)
					)
					(width 0)
					(fill yes)
				)
			)
		)
		(pad "2" smd custom
			(at 0 0.4445 90)
			(size 0.1524 0.1524)
			(layers "F.Cu" "F.Mask" "F.Paste")
			(net "GND")
			(options
				(clearance outline)
				(anchor circle)
			)
			(primitives
				(gr_poly
					(pts
						(arc
							(start 0.3048 -0.2032)
							(mid 0.275042 -0.275042)
							(end 0.2032 -0.3048)
						)
						(arc
							(start -0.2032 -0.3048)
							(mid -0.275042 -0.275042)
							(end -0.3048 -0.2032)
						)
						(arc
							(start -0.3048 0.2032)
							(mid -0.275042 0.275042)
							(end -0.2032 0.3048)
						)
						(arc
							(start 0.2032 0.3048)
							(mid 0.275042 0.275042)
							(end 0.3048 0.2032)
						)
					)
					(width 0)
					(fill yes)
				)
			)
		)
	)
	(footprint ""
		(layer "F.Cu")
		(at 109.467396 -45.633894 90)
		(property "Reference" "R765"
			(at 0 0 90)
			(layer "F.SilkS")
			(hide yes)
			(effects
				(font
					(size 1.27 1.27)
				)
			)
		)
		(property "Value" "4K7R2J-2-GP"
			(at 0.064008 -3.993896 90)
			(unlocked yes)
			(layer "F.Fab")
			(hide yes)
			(effects
				(font
					(size 1.016 1.016)
					(thickness 0.1524)
				)
			)
		)
		(property "Device Type" "R402H16"
			(at 0.064008 -5.517896 90)
			(unlocked yes)
			(layer "F.Fab")
			(hide yes)
			(effects
				(font
					(size 1.016 1.016)
					(thickness 0.1524)
				)
			)
		)
		(duplicate_pad_numbers_are_jumpers no)
		(fp_line
			(start 0.508 -0.9398)
			(end -0.508 -0.9398)
			(stroke
				(width 0.1524)
				(type default)
			)
			(layer "F.SilkS")
		)
		(fp_line
			(start -0.508 -0.9398)
			(end -0.508 0.9398)
			(stroke
				(width 0.1524)
				(type default)
			)
			(layer "F.SilkS")
		)
		(fp_rect
			(start -0.508 0.9398)
			(end 0.508 -0.9398)
			(stroke
				(width 0)
				(type default)
			)
			(fill no)
			(layer "F.CrtYd")
		)
		(fp_rect
			(start -0.508 0.9398)
			(end 0.508 -0.9398)
			(stroke
				(width 0)
				(type default)
			)
			(fill no)
			(layer "F.Fab")
		)
		(pad "1" smd custom
			(at 0 -0.4445 90)
			(size 0.1397 0.1397)
			(layers "F.Cu" "F.Mask" "F.Paste")
			(net "P12V_A")
			(options
				(clearance outline)
				(anchor circle)
			)
			(primitives
				(gr_poly
					(pts
						(arc
							(start -0.1778 -0.2794)
							(mid -0.249642 -0.249642)
							(end -0.2794 -0.1778)
						)
						(arc
							(start -0.2794 0.1778)
							(mid -0.249642 0.249642)
							(end -0.1778 0.2794)
						)
						(arc
							(start 0.1778 0.2794)
							(mid 0.249642 0.249642)
							(end 0.2794 0.1778)
						)
						(arc
							(start 0.2794 -0.1778)
							(mid 0.249642 -0.249642)
							(end 0.1778 -0.2794)
						)
					)
					(width 0)
					(fill yes)
				)
			)
		)
		(pad "2" smd custom
			(at 0 0.4445 90)
			(size 0.1397 0.1397)
			(layers "F.Cu" "F.Mask" "F.Paste")
			(net "SW_HDD_R27")
			(options
				(clearance outline)
				(anchor circle)
			)
			(primitives
				(gr_poly
					(pts
						(arc
							(start -0.1778 -0.2794)
							(mid -0.249642 -0.249642)
							(end -0.2794 -0.1778)
						)
						(arc
							(start -0.2794 0.1778)
							(mid -0.249642 0.249642)
							(end -0.1778 0.2794)
						)
						(arc
							(start 0.1778 0.2794)
							(mid 0.249642 0.249642)
							(end 0.2794 0.1778)
						)
						(arc
							(start 0.2794 -0.1778)
							(mid 0.249642 -0.249642)
							(end 0.1778 -0.2794)
						)
					)
					(width 0)
					(fill yes)
				)
			)
		)
	)
	(footprint ""
		(layer "F.Cu")
		(at 457.6699 -291.127942 -90)
		(property "Reference" "R359"
			(at 0 0 270)
			(layer "F.SilkS")
			(hide yes)
			(effects
				(font
					(size 1.27 1.27)
				)
			)
		)
		(property "Value" "2R6F-GP"
			(at -0.0508 -4.8514 270)
			(unlocked yes)
			(layer "F.Fab")
			(hide yes)
			(effects
				(font
					(size 1.016 1.016)
					(thickness 0.1524)
				)
			)
		)
		(property "Device Type" "R1206H26"
			(at 0 -6.3754 270)
			(unlocked yes)
			(layer "F.Fab")
			(hide yes)
			(effects
				(font
					(size 1.016 1.016)
					(thickness 0.1524)
				)
			)
		)
		(duplicate_pad_numbers_are_jumpers no)
		(fp_line
			(start -1.016 2.2352)
			(end -1.016 -2.2352)
			(stroke
				(width 0.1524)
				(type default)
			)
			(layer "F.SilkS")
		)
		(fp_line
			(start 1.016 2.2352)
			(end -1.016 2.2352)
			(stroke
				(width 0.1524)
				(type default)
			)
			(layer "F.SilkS")
		)
		(fp_line
			(start -1.016 -2.2352)
			(end 1.016 -2.2352)
			(stroke
				(width 0.1524)
				(type default)
			)
			(layer "F.SilkS")
		)
		(fp_line
			(start 1.016 -2.2352)
			(end 1.016 2.2352)
			(stroke
				(width 0.1524)
				(type default)
			)
			(layer "F.SilkS")
		)
		(fp_rect
			(start -1.0922 2.3114)
			(end 1.0922 -2.3114)
			(stroke
				(width 0)
				(type default)
			)
			(fill no)
			(layer "F.CrtYd")
		)
		(fp_poly
			(pts
				(xy -1.0922 -2.3114) (xy 1.0922 -2.3114) (xy 1.0922 2.3114) (xy -1.0922 2.3114)
			)
			(stroke
				(width 0)
				(type default)
			)
			(fill no)
			(layer "F.Fab")
		)
		(pad "1" smd rect
			(at 0 -1.397 270)
			(size 1.651 1.27)
			(layers "F.Cu" "F.Mask" "F.Paste")
			(net "P5V_HDD10")
		)
		(pad "2" smd rect
			(at 0 1.397 270)
			(size 1.651 1.27)
			(layers "F.Cu" "F.Mask" "F.Paste")
			(net "5V_PRE_10")
		)
	)
)
